#ISCELL
  cls sheet_a1 *
  *
#ISCELL
  cls gnd_sg *
  page15_i148
#CELL
  passive capacitor *
  page15_i156
#ISCELL
  cls gnd_sg *
  page15_i157
#ISCELL
  cls gnd_sg *
  page15_i158
#CELL
  discrete diode_2e *
  page15_i159
#CELL
  passive capacitor *
  page15_i160
#ISCELL
  cls gnd_sg *
  page15_i166
#ISCELL
  cls gnd_sg *
  page15_i167
#ISCELL
  cls gnd_sg *
  page15_i168
#CELL
  passive resistor *
  page15_i169
#CELL
  passive resistor *
  page15_i170
#CELL
  passive resistor *
  page15_i171
#CELL
  passive capacitor *
  page15_i172
#CELL
  passive resistor *
  page15_i173
#CELL
  passive resistor *
  page15_i174
#CELL
  passive resistor *
  page15_i183
#ISCELL
  cls gnd_sg *
  page15_i184
#CELL
  passive capacitor *
  page15_i185
#CELL
  passive resistor *
  page15_i186
#ISCELL
  cls gnd_sg *
  page15_i187
#CELL
  passive resistor *
  page15_i188
#ISCELL
  cls gnd_sg *
  page15_i195
#CELL
  passive capacitor *
  page15_i196
#CELL
  passive resistor *
  page15_i197
#CELL
  passive resistor *
  page15_i198
#CELL
  passive resistor *
  page15_i199
#ISCELL
  cls gnd_sg *
  page15_i200
#CELL
  passive capacitor *
  page15_i201
#CELL
  passive resistor *
  page15_i202
#CELL
  passive resistor *
  page15_i203
#CELL
  discrete diode_2 *
  page15_i204
#ISCELL
  cls gnd_sg *
  page15_i205
#CELL
  passive capacitor *
  page15_i206
#CELL
  passive capacitor *
  page15_i207
#ISCELL
  cls vcc *
  page15_i209
#CELL
  passive capacitor *
  page15_i211
#CELL
  stdlogic mp5022cgqv_z_qfn22 *
  page15_i212
#ISCELL
  cls vcc *
  page15_i213
#ISCELL
  cls vcc *
  page15_i215
#CELL
  passive fuse *
  page15_i223
#ISCELL
  cls gnd_sg *
  page15_i226
#CELL
  passive capacitor *
  page15_i229
#CELL
  passive capacitor *
  page15_i230
#CELL
  passive capacitor *
  page15_i231
#CELL
  passive capacitor *
  page15_i232
#CELL
  connector conn_hdr_2x3_m_ra_th *
  page15_i238
#CELL
  discrete diode_3f *
  page15_i239
#CELL
  passive ferritebead *
  page15_i240
#ISCELL
  cls offpage_in *
  page15_i243
#ISCELL
  cls offpage_out *
  page15_i244
#ISCELL
  cls vcc *
  page15_i245
#ISCELL
  cls offpage_in *
  page15_i246
